FILE_TYPE = CONNECTIVITY;
{Allegro Design Entry HDL 17.2-2016 S081 (4005846) 1/11/2022}
"PAGE_NUMBER" = 79;
0"NC";
1"FM_CLK_100M_SLOT2_0_OE_R_N";
2"SCM_SPARE_0";
3"FM_CLK_100M_M2_1_OE_N";
4"FM_CLK_100M_SLOT2_0_OE_N";
5"FM_CLK_100M_M2_1_OE_R_N";
6"FM_CLK_100M_SLOT3_OE_N";
7"FM_CLK_100M_SLOT1_0_OE_N";
8"FM_E1S_2_CLK_OE_R";
9"FM_CLK_100M_SLOT1_1_OE_N";
10"FM_CLK_100M_OCP_OE_R_N";
11"IRQ_HSC_ALERT_N";
12"PWRGD_PVDDCR_SOC_P1";
13"FM_CLK_100M_SLOT2_1_OE_R_N";
14"FM_CLK_100M_M2_2_OE_R_N";
15"PVDDCR_CPU0_P0_EN";
16"FM_E1S_1_CLK_OE_N";
17"FM_CLK_100M_SLOT1_3_OE_R_N";
18"PVDDCR_SOC_P1_EN";
19"FPGA_RDY";
20"SCM_SYS_PWROK";
21"FM_CLK_100M_SLOT1_0_OE_R_N";
22"FM_E1S_2_CLK_OE_N";
23"FM_CLK_100M_SLOT1_1_OE_R_N";
24"FM_CLK_100M_SLOT3_OE_R_N";
25"FM_CLK_100M_OCP_OE_N";
26"FM_CLK_100M_SLOT2_3_OE_R_N";
27"SMB_SCM_1_R1_SCL";
28"FM_CLK_100M_SLOT2_1_OE_N";
29"FM_P3V3_M2_1_EN";
30"SGPIO_SCM_DO_<0>"$PNN"SGPIO_SCM_DO_<0>";
31"PWGD_P3V3_M2_1_R";
32"P3V3_M2_1_EN";
33"PWGD_P3V3_M2_2_R";
34"SGPIO_SCM_LD_<0>"$PNN"SGPIO_SCM_LD_<0>";
35"HPM_STBY_EN";
36"FM_SLOT1_PWRBRK1_N";
37"P3V3_M2_2_EN";
38"FM_SLOT2_PWRBRK1_N";
39"P3V3_OCP_EN_R";
40"FM_SLOT3_PWRBRK_N";
41"FM_SLOT2_PWRBRK0_N";
42"SGPIO_SCM_LD_<1>"$PNN"SGPIO_SCM_LD_<1>";
43"SGPIO_SCM_CLK";
44"SGPIO_SCM_DI_<1>"$PNN"SGPIO_SCM_DI_<1>";
45"FM_SLOT1_PWRBRK1_R_N"CDS_PHYS_NET_NAME"FM_SLOT1_PWRBRK1_R_N";
46"SGPIO_SCM_DI_R<1>"$PNN"SGPIO_SCM_DI_R<1>";
47"HPM_STBY_R_EN";
48"FM_I3C_CPU1_MUX1_SEL";
49"FM_I3C_CPU0_MUX1_OE_R_N";
50"SGPIO_SCM_INTR_R_N";
51"SGPIO_SCM_RESET_N";
52"SGPIO_SCM_DO_<1>"$PNN"SGPIO_SCM_DO_<1>";
53"PWRGD_P12V_STBY_R";
54"SCM_JTAG_MUX_R_S0";
55"FM_I3C_CPU0_MUX0_R_SEL";
56"SCM_JTAG_MUX_R_S1";
57"FM_I3C_CPU1_MUX0_OE_R_N";
58"FM_I3C_CPU0_MUX0_OE_R_N";
59"PWGD_P3V3_OCP";
60"P12V_OCP_EN_R";
61"FM_LED_ACTIVE_E1S_2";
62"FM_LED_ACTIVE_E1S_1";
63"UV_ALERT_N";
64"FM_SLOT3_PWRBRK_R_N"CDS_PHYS_NET_NAME"FM_SLOT3_PWRBRK_R_N";
65"FM_I3C_CPU0_MUX0_OE_N";
66"FM_I3C_CPU1_MUX0_SEL";
67"FM_I3C_CPU1_MUX0_R_SEL";
68"FM_I3C_CPU1_MUX1_OE_R_N";
69"SMB_SCM_0_R1_SDA";
70"JTAG_SCM_PLD_TCK";
71"CPLD_JTAG_EN";
72"CPLD_PROGRAMN";
73"SGPIO_SCM_INTR_N";
74"FM_P3V3_M2_2_EN";
75"FM_SLOT2_PWRBRK0_R_N"CDS_PHYS_NET_NAME"FM_SLOT2_PWRBRK0_R_N";
76"FM_SLOT2_PWRBRK1_R_N"CDS_PHYS_NET_NAME"FM_SLOT2_PWRBRK1_R_N";
77"SGPIO_SCM_DI_<0>"$PNN"SGPIO_SCM_DI_<0>";
78"FM_I3C_CPU1_MUX1_R_SEL";
79"SGPIO_SCM_DI_R<0>"$PNN"SGPIO_SCM_DI_R<0>";
80"FM_SLOT1_PWRBRK0_R_N"CDS_PHYS_NET_NAME"FM_SLOT1_PWRBRK0_R_N";
81"OC_ALERT_N";
82"JTAG_SCM_TRST_R_N";
83"P3V3_OCP_EN";
84"P12V_OCP_EN";
85"FM_CLK_100M_SLOT2_2_OE_R_N";
86"RM_THROTTLE_N";
87"FPGA_DR_FAN_PWM";
88"FPGA_SR_FAN_PWM";
89"SMB_SCM_0_R_SCL";
90"SMB_SCM_0_R_SDA";
91"FM_E1S_3_CLK_OE_R";
92"FM_E1S_4_CLK_OE_R";
93"FM_CLK_100M_SLOT1_2_OE_N";
94"SMB_SCM_1_R_SDA";
95"SMB_SCM_1_R_SCL";
96"FM_CLK_100M_SLOT2_3_OE_N";
97"FM_CLK_100M_SLOT2_2_OE_N";
98"SCM_SYS_PWROK_R";
99"JTAG_SCM_PLD_TDI";
100"JTAG_SCM_PLD_TDO";
101"JTAG_SCM_PLD_TMS";
102"FM_SYS_THROTTLE_R_N"CDS_PHYS_NET_NAME"FM_SYS_THROTTLE_R_N";
103"SMB_CPU0_4_XLTR_SCL";
104"SMB_CPU0_4_XLTR_SDA";
105"FM_SYS_THROTTLE_N"CDS_PHYS_NET_NAME"FM_SYS_THROTTLE_N";
106"JTAG_SCM_TRST_N"CDS_PHYS_NET_NAME"JTAG_SCM_TRST_N";
107"FM_SLOT1_PWRBRK0_N";
108"FM_CLK_100M_SLOT1_3_OE_N";
109"FM_E1S_1_CLK_OE_R";
110"FM_CLK_100M_M2_2_OE_N";
111"FM_LED_ACTIVE_E1S_4";
112"FM_LED_ACTIVE_E1S_3";
113"SMB_CPU0_4_XLTR_R_SDA";
114"SMB_CPU0_4_XLTR_R_SCL";
115"FM_E1S_4_CLK_OE_N";
116"FM_CLK_100M_SLOT1_2_OE_R_N";
117"SCM_SPARE_1";
118"SCM_SYS_PWRBTN_N";
119"SMB_SCM_0_R1_SCL";
120"FM_E1S_3_CLK_OE_N";
121"SMB_SCM_1_R1_SDA";
122"SCM_ROT_CPU_RST_R_N";
123"HPM_STBY_RST_N";
124"SMB_PSU1_ALERT";
125"SMB_PSU2_ALERT";
126"FM_I3C_CPU0_MUX1_SEL";
127"FM_I3C_CPU1_MUX1_OE_N";
128"FM_I3C_CPU0_MUX1_R_SEL";
129"FM_I3C_CPU1_MUX0_OE_N";
130"SCM_JTAG_MUX_S1";
131"FM_I3C_CPU0_MUX1_OE_N";
132"SCM_JTAG_MUX_S0";
133"FM_I3C_CPU0_MUX0_SEL";
%"Q_RES"
"1","(-2975,4950)","2","pure_quanta","I1262";
;
LOCATION"R51"
$SEC"1"
CDS_SEC"1"
VALUE"0"
CDS_LIB"pure_quanta"
BOM_COST"MEM"
WATTAGE"1/16W"
MATERIAL"CHIP"
TOLERANCE"5%"
PART_NUMBER"CS00002JB38"
PACK_TYPE"0402LF"
ROOM"RST_CPU0_PLD_TO_DIMM";
"B"
$PN"2"119;
"A"
$PN"1"89;
%"Q_RES"
"1","(-2975,4900)","2","pure_quanta","I1263";
;
LOCATION"R56"
$SEC"1"
CDS_SEC"1"
VALUE"0"
CDS_LIB"pure_quanta"
BOM_COST"MEM"
WATTAGE"1/16W"
MATERIAL"CHIP"
TOLERANCE"5%"
PART_NUMBER"CS00002JB38"
PACK_TYPE"0402LF"
ROOM"RST_CPU0_PLD_TO_DIMM";
"B"
$PN"2"69;
"A"
$PN"1"90;
%"Q_RES"
"1","(-2975,4850)","0","pure_quanta","I1264";
;
LOCATION"R1056"
$SEC"1"
CDS_SEC"1"
VALUE"33"
BOM_COST"OCP3.0 "
CDS_LIB"pure_quanta"
WATTAGE"1/16W"
MATERIAL"CHIP"
TOLERANCE"5%"
PART_NUMBER"CS03302JB29"
PACK_TYPE"0402LF";
"B"
$PN"2"91;
"A"
$PN"1"120;
%"Q_RES"
"1","(-2975,4800)","0","pure_quanta","I1265";
;
LOCATION"R869"
$SEC"1"
CDS_SEC"1"
VALUE"33"
CDS_LIB"pure_quanta"
BOM_COST"OCP3.0 "
WATTAGE"1/16W"
MATERIAL"CHIP"
TOLERANCE"5%"
PART_NUMBER"CS03302JB29"
PACK_TYPE"0402LF";
"B"
$PN"2"92;
"A"
$PN"1"115;
%"Q_RES"
"1","(-2975,4750)","2","pure_quanta","I1266";
;
LOCATION"R1268"
$SEC"1"
CDS_SEC"1"
VALUE"33"
CDS_LIB"pure_quanta"
BOM_COST"MEM"
WATTAGE"1/16W"
MATERIAL"CHIP"
TOLERANCE"5%"
PART_NUMBER"CS03302JB29"
PACK_TYPE"0402LF"
ROOM"RST_CPU0_PLD_TO_DIMM";
"B"
$PN"2"116;
"A"
$PN"1"93;
%"Q_RES"
"1","(-2975,4600)","2","pure_quanta","I1267";
;
LOCATION"R211"
$SEC"1"
CDS_SEC"1"
VALUE"0"
BOM_COST"MEM"
CDS_LIB"pure_quanta"
WATTAGE"1/16W"
MATERIAL"CHIP"
TOLERANCE"5%"
PART_NUMBER"CS00002JB38"
PACK_TYPE"0402LF"
ROOM"RST_CPU0_PLD_TO_DIMM";
"B"
$PN"2"121;
"A"
$PN"1"94;
%"Q_RES"
"1","(-2975,4650)","2","pure_quanta","I1268";
;
LOCATION"R210"
$SEC"1"
CDS_SEC"1"
VALUE"0"
BOM_COST"MEM"
CDS_LIB"pure_quanta"
WATTAGE"1/16W"
MATERIAL"CHIP"
TOLERANCE"5%"
PART_NUMBER"CS00002JB38"
PACK_TYPE"0402LF"
ROOM"RST_CPU0_PLD_TO_DIMM";
"B"
$PN"2"27;
"A"
$PN"1"95;
%"Q_RES"
"1","(-2975,4200)","2","pure_quanta","I1269";
;
LOCATION"R1273"
$SEC"1"
CDS_SEC"1"
VALUE"33"
CDS_LIB"pure_quanta"
BOM_COST"MEM"
WATTAGE"1/16W"
MATERIAL"CHIP"
TOLERANCE"5%"
PART_NUMBER"CS03302JB29"
PACK_TYPE"0402LF"
ROOM"RST_CPU0_PLD_TO_DIMM";
"B"
$PN"2"26;
"A"
$PN"1"96;
%"Q_RES"
"1","(-2975,4250)","2","pure_quanta","I1270";
;
LOCATION"R1272"
$SEC"1"
CDS_SEC"1"
VALUE"33"
CDS_LIB"pure_quanta"
BOM_COST"MEM"
WATTAGE"1/16W"
MATERIAL"CHIP"
TOLERANCE"5%"
PART_NUMBER"CS03302JB29"
PACK_TYPE"0402LF"
ROOM"RST_CPU0_PLD_TO_DIMM";
"B"
$PN"2"85;
"A"
$PN"1"97;
%"Q_RES"
"1","(-2975,4100)","2","pure_quanta","I1271";
;
LOCATION"R63"
$SEC"1"
CDS_SEC"1"
VALUE"33"
BOM_COST"MEM"
CDS_LIB"pure_quanta"
WATTAGE"1/16W"
MATERIAL"CHIP"
TOLERANCE"5%"
PART_NUMBER"CS03302JB29"
PACK_TYPE"0402LF"
ROOM"RST_CPU0_PLD_TO_DIMM";
"B"
$PN"2"20;
"A"
$PN"1"98;
%"Q_RES"
"1","(-2975,3950)","2","pure_quanta","I1272";
;
LOCATION"R1269"
$SEC"1"
CDS_SEC"1"
VALUE"33"
BOM_COST"MEM"
CDS_LIB"pure_quanta"
WATTAGE"1/16W"
MATERIAL"CHIP"
TOLERANCE"5%"
PART_NUMBER"CS03302JB29"
PACK_TYPE"0402LF"
ROOM"RST_CPU0_PLD_TO_DIMM";
"B"
$PN"2"17;
"A"
$PN"1"108;
%"Q_RES"
"1","(-2975,3900)","0","pure_quanta","I1273";
;
LOCATION"R704"
$SEC"1"
CDS_SEC"1"
VALUE"33"
BOM_COST"OCP3.0 "
CDS_LIB"pure_quanta"
WATTAGE"1/16W"
MATERIAL"CHIP"
TOLERANCE"5%"
PART_NUMBER"CS03302JB29"
PACK_TYPE"0402LF";
"B"
$PN"2"109;
"A"
$PN"1"16;
%"Q_RES"
"1","(-2975,3800)","2","pure_quanta","I1274";
;
LOCATION"R1276"
$SEC"1"
CDS_SEC"1"
VALUE"33"
BOM_COST"MEM"
CDS_LIB"pure_quanta"
WATTAGE"1/16W"
MATERIAL"CHIP"
TOLERANCE"5%"
PART_NUMBER"CS03302JB29"
PACK_TYPE"0402LF"
ROOM"RST_CPU0_PLD_TO_DIMM";
"B"
$PN"2"14;
"A"
$PN"1"110;
%"Q_RES"
"1","(-2975,3650)","2","pure_quanta","I1275";
;
LOCATION"R1267"
$SEC"1"
CDS_SEC"1"
VALUE"33"
CDS_LIB"pure_quanta"
BOM_COST"MEM"
WATTAGE"1/16W"
MATERIAL"CHIP"
TOLERANCE"5%"
PART_NUMBER"CS03302JB29"
PACK_TYPE"0402LF"
ROOM"RST_CPU0_PLD_TO_DIMM";
"B"
$PN"2"23;
"A"
$PN"1"9;
%"Q_RES"
"1","(-2975,3750)","2","pure_quanta","I1276";
;
LOCATION"R1271"
$SEC"1"
CDS_SEC"1"
VALUE"33"
CDS_LIB"pure_quanta"
BOM_COST"MEM"
WATTAGE"1/16W"
MATERIAL"CHIP"
TOLERANCE"5%"
PART_NUMBER"CS03302JB29"
PACK_TYPE"0402LF"
ROOM"RST_CPU0_PLD_TO_DIMM";
"B"
$PN"2"13;
"A"
$PN"1"28;
%"Q_RES"
"1","(-2975,3600)","0","pure_quanta","I1277";
;
LOCATION"R1040"
$SEC"1"
CDS_SEC"1"
VALUE"33"
BOM_COST"OCP3.0 "
CDS_LIB"pure_quanta"
WATTAGE"1/16W"
MATERIAL"CHIP"
TOLERANCE"5%"
PART_NUMBER"CS03302JB29"
PACK_TYPE"0402LF";
"B"
$PN"2"8;
"A"
$PN"1"22;
%"Q_RES"
"1","(-2975,3500)","2","pure_quanta","I1278";
;
LOCATION"R1254"
$SEC"1"
CDS_SEC"1"
VALUE"33"
CDS_LIB"pure_quanta"
BOM_COST"MEM"
WATTAGE"1/16W"
MATERIAL"CHIP"
TOLERANCE"5%"
PART_NUMBER"CS03302JB29"
PACK_TYPE"0402LF"
ROOM"RST_CPU0_PLD_TO_DIMM";
"B"
$PN"2"21;
"A"
$PN"1"7;
%"Q_RES"
"1","(-2975,3450)","2","pure_quanta","I1279";
;
LOCATION"R1274"
$SEC"1"
CDS_SEC"1"
VALUE"33"
CDS_LIB"pure_quanta"
ROOM"RST_CPU0_PLD_TO_DIMM"
PACK_TYPE"0402LF"
PART_NUMBER"CS03302JB29"
TOLERANCE"5%"
MATERIAL"CHIP"
WATTAGE"1/16W"
BOM_COST"MEM";
"B"
$PN"2"24;
"A"
$PN"1"6;
%"Q_RES"
"1","(-2975,3150)","2","pure_quanta","I1280";
;
LOCATION"R1270"
$SEC"1"
CDS_SEC"1"
VALUE"33"
CDS_LIB"pure_quanta"
BOM_COST"MEM"
WATTAGE"1/16W"
MATERIAL"CHIP"
TOLERANCE"5%"
PART_NUMBER"CS03302JB29"
PACK_TYPE"0402LF"
ROOM"RST_CPU0_PLD_TO_DIMM";
"B"
$PN"2"1;
"A"
$PN"1"4;
%"Q_RES"
"1","(-2975,3250)","2","pure_quanta","I1281";
;
LOCATION"R1277"
$SEC"1"
CDS_SEC"1"
VALUE"33"
CDS_LIB"pure_quanta"
BOM_COST"MEM"
WATTAGE"1/16W"
MATERIAL"CHIP"
TOLERANCE"5%"
PART_NUMBER"CS03302JB29"
PACK_TYPE"0402LF"
ROOM"RST_CPU0_PLD_TO_DIMM";
"B"
$PN"2"5;
"A"
$PN"1"3;
%"Q_RES"
"1","(-2975,3000)","2","pure_quanta","I1282";
;
LOCATION"R1275"
$SEC"1"
CDS_SEC"1"
VALUE"33"
CDS_LIB"pure_quanta"
BOM_COST"MEM"
WATTAGE"1/16W"
MATERIAL"CHIP"
TOLERANCE"5%"
PART_NUMBER"CS03302JB29"
PACK_TYPE"0402LF"
ROOM"RST_CPU0_PLD_TO_DIMM";
"B"
$PN"2"10;
"A"
$PN"1"25;
%"LCMXO3D9400HC5BG484C"
"3","(-5025,3850)","0","pure_quanta","I1289";
;
LOCATION"U18"
$SEC"3"
CDS_SEC"3"
PART_TYPE"SMLF"
MATERIAL"IC"
VALUE"LCMXO3D-9400HC-5BG484C"
PART_NUMBER"AJ094000T05"
CDS_LIB"pure_quanta"
NEEDS_NO_SIZE"TRUE"
CDS_LMAN_SYM_OUTLINE"-900,1250,900,-1250";
"PT43D"
$PN"C20"0;
"PT43C"
$PN"C19"0;
"PT42D"
$PN"G15"2;
"PT42C"
$PN"F15"1;
"PT42B"
$PN"B20"0;
"PT42A"
$PN"A19"5;
"PT41D"
$PN"D18"0;
"PT41C"
$PN"C18"0;
"PT40D"
$PN"D17"0;
"PT40C"
$PN"E16"22;
"PT40B"
$PN"B18"23;
"PT40A"
$PN"A17"12;
"PT39D"
$PN"D16"13;
"PT39C"
$PN"C17"14;
"PT39B"
$PN"B17"15;
"PT39A"
$PN"A16"16;
"PT38D"
$PN"D15"17;
"PT38C"
$PN"C15"18;
"PT38B"
$PN"B15"19;
"PT38A"
$PN"A15"20;
"PT30D"
$PN"D14"88;
"PT30C"
$PN"C14"87;
"PT30B"
$PN"B14"125;
"PT30A"
$PN"A14"124;
"PT29D"
$PN"D13"123;
"PT29C"
$PN"C13"122;
"PT29B"
$PN"B13"121;
"PT29A"
$PN"A13"27;
"PT28D"
$PN"F13"117;
"PT28C"
$PN"E13"116;
"PT27B"
$PN"E12"118;
"PT27A"
$PN"D12"86;
"PT24D"
$PN"D11"82;
"PT24C"
$PN"E11"102;
"PT24B"
$PN"A11"111;
"PT24A"
$PN"B11"112;
"PT23D"
$PN"F11"113;
"PT23C"
$PN"G11"114;
"PT21D"
$PN"G9"80;
"PT21C"
$PN"F9"84;
"PT21B"
$PN"A9"59;
"PT21A"
$PN"B9"83;
"PT20D"
$PN"D9"64;
"PT20C"
$PN"C9"76;
"PT20B"
$PN"A8"75;
"PT20A"
$PN"B8"74;
"PT14D"
$PN"D7"34;
"PT14C"
$PN"C6"46;
"PT14B"
$PN"A7"33;
"PT14A"
$PN"B6"29;
"PT13D"
$PN"E7"30;
"PT13C"
$PN"D6"43;
"PT13B"
$PN"A6"31;
"PT13A"
$PN"B5"42;
"PT12D"
$PN"C5"0;
"PT12C"
$PN"D5"78;
"PT12B"
$PN"A5"51;
"PT12A"
$PN"B4"52;
"PT10D"
$PN"C4"49;
"PT10C"
$PN"C3"55;
"PT10B"
$PN"A3"56;
"PT10A"
$PN"B2"57;
"PT11D"
$PN"G8"50;
"PT11C"
$PN"F8"53;
"PT22B"
$PN"E10"62;
"PT22A"
$PN"F10"61;
"PT11B"
$PN"A4"79;
"PT11A"
$PN"B3"54;
"PT15A"
$PN"C8"47;
"PT9A"
$PN"B1"58;
"PT9C"
$PN"E6"68;
"PT9B"
$PN"A2"67;
"PT9D"
$PN"F7"128;
"PT15B"
$PN"D8"45;
"PT23A||PCLKT0_1"
$PN"B10"63;
"PT23B||PCLKC0_1"
$PN"A10"81;
"PT44A"
$PN"A21"0;
"PT44B"
$PN"B22"0;
"PT27C||SCL||PCLKT0_0"
$PN"B12"119;
"PT27D||SDA||PCLKC0_0"
$PN"A12"69;
"PT28A"
$PN"G12"120;
"PT28B"
$PN"F12"115;
"PT31A"
$PN"G14"85;
"PT31B"
$PN"F14"26;
"PT41A"
$PN"A18"21;
"PT41B"
$PN"B19"24;
"PT43A"
$PN"A20"10;
"PT43B"
$PN"B21"11;
%"LCMXO3D9400HC5BG484C"
"4","(-5575,1250)","0","pure_quanta","I1290";
;
LOCATION"U18"
$SEC"4"
CDS_SEC"4"
MATERIAL"IC"
VALUE"LCMXO3D-9400HC-5BG484C"
PART_NUMBER"AJ094000T05"
PART_TYPE"SMLF"
CDS_LIB"pure_quanta"
NEEDS_NO_SIZE"TRUE"
CDS_LMAN_SYM_OUTLINE"-400,250,400,-250";
"PT31C||JTAGENB"
$PN"E14"71;
"PT44D||DONE"
$PN"E17"0;
"PT44C||INITN"
$PN"F16"0;
"PT31D||PROGRAMN"
$PN"E15"72;
"PT22D||TMS"
$PN"C10"101;
"PT22C||TCK"
$PN"D10"70;
"PT15D||TDI"
$PN"E9"100;
"PT15C||TDO"
$PN"E8"99;
%"Q_RES"
"1","(-7050,4950)","2","pure_quanta","I1291";
;
LOCATION"R170"
$SEC"1"
CDS_SEC"1"
VALUE"33"
CDS_LIB"pure_quanta"
BOM_COST"MEM"
WATTAGE"1/16W"
MATERIAL"CHIP"
TOLERANCE"5%"
PART_NUMBER"CS03302JB29"
PACK_TYPE"0402LF"
ROOM"RST_CPU0_PLD_TO_DIMM";
"B"
$PN"2"66;
"A"
$PN"1"67;
%"Q_RES"
"1","(-7050,5000)","2","pure_quanta","I1292";
;
LOCATION"R163"
$SEC"1"
CDS_SEC"1"
VALUE"33"
BOM_COST"MEM"
CDS_LIB"pure_quanta"
WATTAGE"1/16W"
MATERIAL"CHIP"
TOLERANCE"5%"
PART_NUMBER"CS03302JB29"
PACK_TYPE"0402LF"
ROOM"RST_CPU0_PLD_TO_DIMM";
"B"
$PN"2"65;
"A"
$PN"1"58;
%"Q_RES"
"1","(-7050,4850)","2","pure_quanta","I1293";
;
LOCATION"R166"
$SEC"1"
CDS_SEC"1"
VALUE"33"
BOM_COST"MEM"
CDS_LIB"pure_quanta"
WATTAGE"1/16W"
MATERIAL"CHIP"
TOLERANCE"5%"
PART_NUMBER"CS03302JB29"
PACK_TYPE"0402LF"
ROOM"RST_CPU0_PLD_TO_DIMM";
"B"
$PN"2"126;
"A"
$PN"1"128;
%"Q_RES"
"1","(-7050,4900)","2","pure_quanta","I1294";
;
LOCATION"R171"
$SEC"1"
CDS_SEC"1"
VALUE"33"
CDS_LIB"pure_quanta"
BOM_COST"MEM"
WATTAGE"1/16W"
MATERIAL"CHIP"
TOLERANCE"5%"
PART_NUMBER"CS03302JB29"
PACK_TYPE"0402LF"
ROOM"RST_CPU0_PLD_TO_DIMM";
"B"
$PN"2"127;
"A"
$PN"1"68;
%"Q_RES"
"1","(-7050,4800)","2","pure_quanta","I1295";
;
LOCATION"R169"
$SEC"1"
CDS_SEC"1"
VALUE"33"
CDS_LIB"pure_quanta"
BOM_COST"MEM"
WATTAGE"1/16W"
MATERIAL"CHIP"
TOLERANCE"5%"
PART_NUMBER"CS03302JB29"
PACK_TYPE"0402LF"
ROOM"RST_CPU0_PLD_TO_DIMM";
"B"
$PN"2"129;
"A"
$PN"1"57;
%"Q_RES"
"1","(-7050,4750)","2","pure_quanta","I1296";
;
LOCATION"R50"
$SEC"1"
CDS_SEC"1"
VALUE"33"
BOM_COST"MEM"
CDS_LIB"pure_quanta"
WATTAGE"1/16W"
MATERIAL"CHIP"
TOLERANCE"5%"
PART_NUMBER"CS03302JB29"
PACK_TYPE"0402LF"
ROOM"RST_CPU0_PLD_TO_DIMM";
"B"
$PN"2"130;
"A"
$PN"1"56;
%"Q_RES"
"1","(-7050,4700)","2","pure_quanta","I1297";
;
LOCATION"R164"
$SEC"1"
CDS_SEC"1"
VALUE"33"
CDS_LIB"pure_quanta"
BOM_COST"MEM"
WATTAGE"1/16W"
MATERIAL"CHIP"
TOLERANCE"5%"
PART_NUMBER"CS03302JB29"
PACK_TYPE"0402LF"
ROOM"RST_CPU0_PLD_TO_DIMM";
"B"
$PN"2"133;
"A"
$PN"1"55;
%"Q_RES"
"1","(-7050,4650)","2","pure_quanta","I1298";
;
LOCATION"R165"
$SEC"1"
CDS_SEC"1"
VALUE"33"
BOM_COST"MEM"
CDS_LIB"pure_quanta"
WATTAGE"1/16W"
MATERIAL"CHIP"
TOLERANCE"5%"
PART_NUMBER"CS03302JB29"
PACK_TYPE"0402LF"
ROOM"RST_CPU0_PLD_TO_DIMM";
"B"
$PN"2"131;
"A"
$PN"1"49;
%"Q_RES"
"1","(-7050,4550)","2","pure_quanta","I1299";
;
LOCATION"R167"
$SEC"1"
CDS_SEC"1"
VALUE"0"
BOM_COST"MEM"
CDS_LIB"pure_quanta"
WATTAGE"1/16W"
MATERIAL"CHIP"
TOLERANCE"5%"
PART_NUMBER"CS00002JB38"
PACK_TYPE"0402LF"
ROOM"RST_CPU0_PLD_TO_DIMM";
"B"
$PN"2"77;
"A"
$PN"1"79;
%"Q_RES"
"1","(-7050,4600)","2","pure_quanta","I1300";
;
LOCATION"R49"
$SEC"1"
CDS_SEC"1"
VALUE"33"
ROOM"RST_CPU0_PLD_TO_DIMM"
PACK_TYPE"0402LF"
PART_NUMBER"CS03302JB29"
TOLERANCE"5%"
MATERIAL"CHIP"
WATTAGE"1/16W"
BOM_COST"MEM"
CDS_LIB"pure_quanta";
"B"
$PN"2"132;
"A"
$PN"1"54;
%"Q_RES"
"1","(-7050,4450)","2","pure_quanta","I1301";
;
LOCATION"R58"
$SEC"1"
CDS_SEC"1"
VALUE"33"
BOM_COST"MEM"
CDS_LIB"pure_quanta"
WATTAGE"1/16W"
MATERIAL"CHIP"
TOLERANCE"5%"
PART_NUMBER"CS03302JB29"
PACK_TYPE"0402LF"
ROOM"RST_CPU0_PLD_TO_DIMM";
"B"
$PN"2"73;
"A"
$PN"1"50;
%"Q_RES"
"1","(-7050,4300)","2","pure_quanta","I1302";
;
LOCATION"R172"
$SEC"1"
CDS_SEC"1"
VALUE"33"
ROOM"RST_CPU0_PLD_TO_DIMM"
PACK_TYPE"0402LF"
PART_NUMBER"CS03302JB29"
TOLERANCE"5%"
MATERIAL"CHIP"
WATTAGE"1/16W"
BOM_COST"MEM"
CDS_LIB"pure_quanta";
"B"
$PN"2"48;
"A"
$PN"1"78;
%"Q_RES"
"1","(-7050,4000)","2","pure_quanta","I1303";
;
LOCATION"R1310"
$SEC"1"
CDS_SEC"1"
VALUE"33"
CDS_LIB"pure_quanta"
ROOM"RST_CPU0_PLD_TO_DIMM"
PACK_TYPE"0402LF"
PART_NUMBER"CS03302JB29"
TOLERANCE"5%"
MATERIAL"CHIP"
WATTAGE"1/16W"
BOM_COST"MEM";
"B"
$PN"2"32;
"A"
$PN"1"29;
%"Q_RES"
"1","(-7050,3900)","2","pure_quanta","I1304";
;
LOCATION"R168"
$SEC"1"
CDS_SEC"1"
VALUE"0"
BOM_COST"MEM"
CDS_LIB"pure_quanta"
WATTAGE"1/16W"
MATERIAL"CHIP"
TOLERANCE"5%"
PART_NUMBER"CS00002JB38"
PACK_TYPE"0402LF"
ROOM"RST_CPU0_PLD_TO_DIMM";
"B"
$PN"2"44;
"A"
$PN"1"46;
%"Q_RES"
"1","(-7050,3700)","2","pure_quanta","I1305";
;
LOCATION"R1312"
$SEC"1"
CDS_SEC"1"
VALUE"33"
BOM_COST"MEM"
CDS_LIB"pure_quanta"
WATTAGE"1/16W"
MATERIAL"CHIP"
TOLERANCE"5%"
PART_NUMBER"CS03302JB29"
PACK_TYPE"0402LF"
ROOM"RST_CPU0_PLD_TO_DIMM";
"B"
$PN"2"37;
"A"
$PN"1"74;
%"Q_RES"
"1","(-7050,3750)","2","pure_quanta","I1306";
;
LOCATION"R60"
$SEC"1"
CDS_SEC"1"
VALUE"33"
MATERIAL"EMPTY"
ROOM"RST_CPU0_PLD_TO_DIMM"
PACK_TYPE"0402LF"
PART_NUMBER"CS03302JB29"
TOLERANCE"5%"
WATTAGE"1/16W"
BOM_COST"MEM"
CDS_LIB"pure_quanta";
"B"
$PN"2"36;
"A"
$PN"1"45;
%"Q_RES"
"1","(-7050,3650)","2","pure_quanta","I1307";
;
LOCATION"R61"
$SEC"1"
CDS_SEC"1"
VALUE"33"
MATERIAL"EMPTY"
ROOM"RST_CPU0_PLD_TO_DIMM"
PACK_TYPE"0402LF"
PART_NUMBER"CS03302JB29"
TOLERANCE"5%"
WATTAGE"1/16W"
CDS_LIB"pure_quanta"
BOM_COST"MEM";
"B"
$PN"2"41;
"A"
$PN"1"75;
%"Q_RES"
"1","(-7050,3600)","2","pure_quanta","I1308";
;
LOCATION"R62"
$SEC"1"
CDS_SEC"1"
VALUE"33"
MATERIAL"EMPTY"
ROOM"RST_CPU0_PLD_TO_DIMM"
PACK_TYPE"0402LF"
PART_NUMBER"CS03302JB29"
TOLERANCE"5%"
WATTAGE"1/16W"
BOM_COST"MEM"
CDS_LIB"pure_quanta";
"B"
$PN"2"38;
"A"
$PN"1"76;
%"Q_RES"
"1","(-7050,3550)","2","pure_quanta","I1309";
;
LOCATION"R1129"
$SEC"1"
CDS_SEC"1"
VALUE"33"
MATERIAL"EMPTY"
ROOM"RST_CPU0_PLD_TO_DIMM"
PACK_TYPE"0402LF"
PART_NUMBER"CS03302JB29"
TOLERANCE"5%"
WATTAGE"1/16W"
BOM_COST"MEM"
CDS_LIB"pure_quanta";
"B"
$PN"2"40;
"A"
$PN"1"64;
%"Q_RES"
"1","(-7050,3400)","2","pure_quanta","I1310";
;
LOCATION"R23"
$SEC"1"
CDS_SEC"1"
VALUE"33"
CDS_LIB"pure_quanta"
BOM_COST"MEM"
WATTAGE"1/16W"
MATERIAL"CHIP"
TOLERANCE"5%"
PART_NUMBER"CS03302JB29"
PACK_TYPE"0402LF"
ROOM"RST_CPU0_PLD_TO_DIMM";
"B"
$PN"2"39;
"A"
$PN"1"83;
%"Q_RES"
"1","(-7050,3250)","2","pure_quanta","I1311";
;
LOCATION"R154"
$SEC"1"
CDS_SEC"1"
MATERIAL"EMPTY"
VALUE"33"
ROOM"RST_CPU0_PLD_TO_DIMM"
PACK_TYPE"0402LF"
PART_NUMBER"CS03302JB29"
TOLERANCE"5%"
WATTAGE"1/16W"
BOM_COST"MEM"
CDS_LIB"pure_quanta";
"B"
$PN"2"107;
"A"
$PN"1"80;
%"Q_RES"
"1","(-7050,3300)","2","pure_quanta","I1312";
;
LOCATION"R152"
$SEC"1"
CDS_SEC"1"
VALUE"33"
CDS_LIB"pure_quanta"
BOM_COST"MEM"
WATTAGE"1/16W"
MATERIAL"CHIP"
TOLERANCE"5%"
PART_NUMBER"CS03302JB29"
PACK_TYPE"0402LF"
ROOM"RST_CPU0_PLD_TO_DIMM";
"B"
$PN"2"60;
"A"
$PN"1"84;
%"Q_RES"
"1","(-7050,3000)","2","pure_quanta","I1345";
;
LOCATION"R70"
$SEC"1"
CDS_SEC"1"
VALUE"0"
BOM_COST"MEM"
CDS_LIB"pure_quanta"
WATTAGE"1/16W"
MATERIAL"CHIP"
TOLERANCE"5%"
PART_NUMBER"CS00002JB38"
PACK_TYPE"0402LF"
ROOM"RST_CPU0_PLD_TO_DIMM";
"B"
$PN"2"103;
"A"
$PN"1"114;
%"Q_RES"
"1","(-7050,2950)","2","pure_quanta","I1346";
;
LOCATION"R493"
$SEC"1"
CDS_SEC"1"
VALUE"0"
CDS_LIB"pure_quanta"
BOM_COST"MEM"
WATTAGE"1/16W"
MATERIAL"CHIP"
TOLERANCE"5%"
PART_NUMBER"CS00002JB38"
PACK_TYPE"0402LF"
ROOM"RST_CPU0_PLD_TO_DIMM";
"B"
$PN"2"104;
"A"
$PN"1"113;
%"Q_RES"
"1","(-7050,2750)","2","pure_quanta","I1347";
;
LOCATION"R992"
$SEC"1"
CDS_SEC"1"
VALUE"33"
BOM_COST"MEM"
CDS_LIB"pure_quanta"
WATTAGE"1/16W"
MATERIAL"CHIP"
TOLERANCE"5%"
PART_NUMBER"CS03302JB29"
PACK_TYPE"0402LF"
ROOM"RST_CPU0_PLD_TO_DIMM";
"B"
$PN"2"105;
"A"
$PN"1"102;
%"Q_RES"
"1","(-7050,2700)","2","pure_quanta","I1348";
;
LOCATION"R160"
$SEC"1"
CDS_SEC"1"
VALUE"33"
CDS_LIB"pure_quanta"
BOM_COST"MEM"
WATTAGE"1/16W"
MATERIAL"CHIP"
TOLERANCE"5%"
PART_NUMBER"CS03302JB29"
PACK_TYPE"0402LF"
ROOM"RST_CPU0_PLD_TO_DIMM";
"B"
$PN"2"106;
"A"
$PN"1"82;
%"Q_RES"
"1","(-7050,3800)","2","pure_quanta","I1362";
;
$LOCATION"R1548"
CDS_LOCATION"R1548"
$SEC"1"
CDS_SEC"1"
VALUE"33"
BOM_COST"MEM"
WATTAGE"1/16W"
MATERIAL"CHIP"
TOLERANCE"5%"
PART_NUMBER"CS03302JB29"
PACK_TYPE"0402LF"
ROOM"RST_CPU0_PLD_TO_DIMM"
CDS_LIB"pure_quanta";
"B"
$PN"2"35;
"A"
$PN"1"47;
END.
